# TIMECARD (Time Appliance Project (Time Card)) — schematic netlist excerpt (pin names and nets, part order shuffled) for the footprints in the layout excerpt that follows; sources: Cadence DE-HDL packaged netlist, KiCad conversion of R4006-B0001-02_R01.brd

R131  RESISTOR  100OHM 1%  pkg SMC_0402R_H016  page 24 : \1\ = R_FT4232_CHD_TX ; \2\ = FT4232_CHD_TX
R208  RESISTOR  330OHM 1%  pkg SMC_0402R_H016  page 26 : \1\ = UNNAMED_14_OPTICAL_I292_A ; \2\ = FPGA_DONE

(kicad_pcb
	(version 20260206)
	(generator "pcbnew")
	(generator_version "10.0")
	(general
		(thickness 1.6)
		(legacy_teardrops no)
	)
	(paper "A4")
	(title_block
		(title "timecard-production-celestica-r4006 — R4006-B0001-02_R01.brd")
		(comment 1 "Time Appliance Project (Time Card) / footprints 855-856 of 1113")
	)
	(layers
		(0 "F.Cu" signal "TOP")
		(4 "In1.Cu" signal "L02_GND1")
		(6 "In2.Cu" signal "L03_SIG1")
		(8 "In3.Cu" signal "L04_GND2")
		(10 "In4.Cu" signal "L05_VCC1")
		(12 "In5.Cu" signal "L06_VCC2")
		(14 "In6.Cu" signal "L07_GND3")
		(16 "In7.Cu" signal "L08_SIG2")
		(18 "In8.Cu" signal "L09_GND4")
		(2 "B.Cu" signal "BOTTOM")
		(9 "F.Adhes" user "F.Adhesive")
		(11 "B.Adhes" user "B.Adhesive")
		(13 "F.Paste" user "Package Geometry/Pastemask Top")
		(15 "B.Paste" user "Package Geometry/Pastemask Bottom")
		(5 "F.SilkS" user "Ref Des/Silkscreen Top")
		(7 "B.SilkS" user "Ref Des/Silkscreen Bottom")
		(1 "F.Mask" user "Board Geometry/Soldermask Top")
		(3 "B.Mask" user "Board Geometry/Soldermask Bottom")
		(17 "Dwgs.User" user "User.Drawings")
		(19 "Cmts.User" user "User.Comments")
		(21 "Eco1.User" user "User.Eco1")
		(23 "Eco2.User" user "User.Eco2")
		(25 "Edge.Cuts" user "Board Geometry/Outline")
		(27 "Margin" user)
		(31 "F.CrtYd" user "Package Geometry/Place Bound Top")
		(29 "B.CrtYd" user "Package Geometry/Place Bound Bottom")
		(35 "F.Fab" user "Ref Des/Assembly Top")
		(33 "B.Fab" user "Ref Des/Assembly Bottom")
	)
	(footprint ""
		(layer "B.Cu")
		(at 32.512 -79.121 90)
		(property "Reference" "R131"
			(at 0.254 1.10363 270)
			(unlocked yes)
			(layer "B.SilkS")
			(effects
				(font
					(size 0.7874 0.5842)
					(thickness 0.1524)
				)
				(justify mirror)
			)
		)
		(property "Value" "VAL*"
			(at -0.02032 2.13233 90)
			(unlocked yes)
			(layer "B.Fab")
			(hide yes)
			(effects
				(font
					(size 0.7874 0.5842)
					(thickness 0.1524)
				)
				(justify mirror)
			)
		)
		(property "Tolerance" "TOL*"
			(at -0.044704 3.05435 90)
			(unlocked yes)
			(layer "Cmts.User")
			(hide yes)
			(effects
				(font
					(size 0.7874 0.5842)
					(thickness 0.1524)
				)
				(justify mirror)
			)
		)
		(property "User Part Number" "PARTNUM*"
			(at -0.02032 4.024884 90)
			(unlocked yes)
			(layer "Cmts.User")
			(hide yes)
			(effects
				(font
					(size 0.7874 0.5842)
					(thickness 0.1524)
				)
				(justify mirror)
			)
		)
		(property "Device Type" "RESISTOR-G155-11000-01,100OHM,A"
			(at -0.008382 1.210564 90)
			(unlocked yes)
			(layer "B.Fab")
			(hide yes)
			(effects
				(font
					(size 0.7874 0.5842)
					(thickness 0.1524)
				)
				(justify mirror)
			)
		)
		(duplicate_pad_numbers_are_jumpers no)
		(fp_line
			(start 1.143 -0.5588)
			(end 1.143 0.5588)
			(stroke
				(width 0.1)
				(type default)
			)
			(layer "B.SilkS")
		)
		(fp_line
			(start -1.143 -0.5588)
			(end 1.143 -0.5588)
			(stroke
				(width 0.1)
				(type default)
			)
			(layer "B.SilkS")
		)
		(fp_line
			(start 1.143 0.5588)
			(end -1.143 0.5588)
			(stroke
				(width 0.1)
				(type default)
			)
			(layer "B.SilkS")
		)
		(fp_line
			(start -1.143 0.5588)
			(end -1.143 -0.5588)
			(stroke
				(width 0.1)
				(type default)
			)
			(layer "B.SilkS")
		)
		(fp_rect
			(start 1.143 -0.5588)
			(end -1.143 0.5588)
			(stroke
				(width 0)
				(type default)
			)
			(fill no)
			(layer "B.CrtYd")
		)
		(fp_line
			(start 0.508 -0.3048)
			(end 0.508 0.3048)
			(stroke
				(width 0.1)
				(type default)
			)
			(layer "B.Fab")
		)
		(fp_line
			(start -0.508 -0.3048)
			(end 0.508 -0.3048)
			(stroke
				(width 0.1)
				(type default)
			)
			(layer "B.Fab")
		)
		(fp_line
			(start 0.508 0.3048)
			(end -0.508 0.3048)
			(stroke
				(width 0.1)
				(type default)
			)
			(layer "B.Fab")
		)
		(fp_line
			(start -0.508 0.3048)
			(end -0.508 -0.3048)
			(stroke
				(width 0.1)
				(type default)
			)
			(layer "B.Fab")
		)
		(pad "1" smd rect
			(at 0.5334 0 270)
			(size 0.7112 0.6096)
			(layers "B.Cu" "B.Mask" "B.Paste")
			(net "R_FT4232_CHD_TX")
		)
		(pad "2" smd rect
			(at -0.5334 0 270)
			(size 0.7112 0.6096)
			(layers "B.Cu" "B.Mask" "B.Paste")
			(net "FT4232_CHD_TX")
		)
		(zone
			(layer "B.Cu")
			(hatch none 0.5)
			(connect_pads
				(clearance 0)
			)
			(min_thickness 0.25)
			(keepout
				(tracks allowed)
				(vias not_allowed)
				(pads allowed)
				(copperpour not_allowed)
				(footprints allowed)
			)
			(placement
				(enabled no)
				(sheetname "")
			)
			(fill
				(thermal_gap 0.5)
				(thermal_bridge_width 0.5)
				(island_removal_mode 0)
			)
			(polygon
				(pts
					(xy 32.2072 -79.1972) (xy 32.2072 -79.0448) (xy 32.8168 -79.0448) (xy 32.8168 -79.1972)
				)
			)
		)
	)
	(footprint ""
		(layer "B.Cu")
		(at 135.2042 -106.172254 90)
		(property "Reference" "R208"
			(at -7.747254 0.90043 270)
			(unlocked yes)
			(layer "B.SilkS")
			(effects
				(font
					(size 0.7874 0.5842)
					(thickness 0.1524)
				)
				(justify mirror)
			)
		)
		(property "Value" "VAL*"
			(at -0.02032 2.13233 90)
			(unlocked yes)
			(layer "B.Fab")
			(hide yes)
			(effects
				(font
					(size 0.7874 0.5842)
					(thickness 0.1524)
				)
				(justify mirror)
			)
		)
		(property "Device Type" "RESISTOR-G155-13300-01,330OHM,A"
			(at -0.008382 1.210564 90)
			(unlocked yes)
			(layer "B.Fab")
			(hide yes)
			(effects
				(font
					(size 0.7874 0.5842)
					(thickness 0.1524)
				)
				(justify mirror)
			)
		)
		(property "User Part Number" "PARTNUM*"
			(at -0.02032 4.024884 90)
			(unlocked yes)
			(layer "Cmts.User")
			(hide yes)
			(effects
				(font
					(size 0.7874 0.5842)
					(thickness 0.1524)
				)
				(justify mirror)
			)
		)
		(property "Tolerance" "TOL*"
			(at -0.044704 3.05435 90)
			(unlocked yes)
			(layer "Cmts.User")
			(hide yes)
			(effects
				(font
					(size 0.7874 0.5842)
					(thickness 0.1524)
				)
				(justify mirror)
			)
		)
		(duplicate_pad_numbers_are_jumpers no)
		(fp_line
			(start 1.143 -0.5588)
			(end 1.143 0.5588)
			(stroke
				(width 0.1)
				(type default)
			)
			(layer "B.SilkS")
		)
		(fp_line
			(start -1.143 -0.5588)
			(end 1.143 -0.5588)
			(stroke
				(width 0.1)
				(type default)
			)
			(layer "B.SilkS")
		)
		(fp_line
			(start 1.143 0.5588)
			(end -1.143 0.5588)
			(stroke
				(width 0.1)
				(type default)
			)
			(layer "B.SilkS")
		)
		(fp_line
			(start -1.143 0.5588)
			(end -1.143 -0.5588)
			(stroke
				(width 0.1)
				(type default)
			)
			(layer "B.SilkS")
		)
		(fp_rect
			(start -1.143 -0.5588)
			(end 1.143 0.5588)
			(stroke
				(width 0)
				(type default)
			)
			(fill no)
			(layer "B.CrtYd")
		)
		(fp_line
			(start 0.508 -0.3048)
			(end 0.508 0.3048)
			(stroke
				(width 0.1)
				(type default)
			)
			(layer "B.Fab")
		)
		(fp_line
			(start -0.508 -0.3048)
			(end 0.508 -0.3048)
			(stroke
				(width 0.1)
				(type default)
			)
			(layer "B.Fab")
		)
		(fp_line
			(start 0.508 0.3048)
			(end -0.508 0.3048)
			(stroke
				(width 0.1)
				(type default)
			)
			(layer "B.Fab")
		)
		(fp_line
			(start -0.508 0.3048)
			(end -0.508 -0.3048)
			(stroke
				(width 0.1)
				(type default)
			)
			(layer "B.Fab")
		)
		(pad "1" smd rect
			(at 0.5334 0 270)
			(size 0.7112 0.6096)
			(layers "B.Cu" "B.Mask" "B.Paste")
			(net "UNNAMED_14_OPTICAL_I292_A")
		)
		(pad "2" smd rect
			(at -0.5334 0 270)
			(size 0.7112 0.6096)
			(layers "B.Cu" "B.Mask" "B.Paste")
			(net "FPGA_DONE")
		)
		(zone
			(layer "B.Cu")
			(hatch none 0.5)
			(connect_pads
				(clearance 0)
			)
			(min_thickness 0.25)
			(keepout
				(tracks allowed)
				(vias not_allowed)
				(pads allowed)
				(copperpour not_allowed)
				(footprints allowed)
			)
			(placement
				(enabled no)
				(sheetname "")
			)
			(fill
				(thermal_gap 0.5)
				(thermal_bridge_width 0.5)
				(island_removal_mode 0)
			)
			(polygon
				(pts
					(xy 134.8994 -106.096054) (xy 135.509 -106.096054) (xy 135.509 -106.248454) (xy 134.8994 -106.248454)
				)
			)
		)
	)
)
